(kicad_pcb
	(version 20260206)
	(generator "pcbnew")
	(generator_version "10.0")
	(general
		(thickness 1.6)
		(legacy_teardrops no)
	)
	(paper "A4")
	(title_block
		(title "04192023_DAF0TMB3IC0_F0TG_MB_C_brd_V02_OCP.brd")
		(comment 1 "Grand Teton / footprints 7867-7874 of 8354")
	)
	(layers
		(0 "F.Cu" signal "TOP")
		(4 "In1.Cu" signal "GND")
		(6 "In2.Cu" signal "IN1")
		(8 "In3.Cu" signal "GND1")
		(10 "In4.Cu" signal "IN2")
		(12 "In5.Cu" signal "GND2")
		(14 "In6.Cu" signal "IN3")
		(16 "In7.Cu" signal "GND3")
		(18 "In8.Cu" signal "VCC")
		(20 "In9.Cu" signal "VCC1")
		(22 "In10.Cu" signal "GND4")
		(24 "In11.Cu" signal "IN4")
		(26 "In12.Cu" signal "GND5")
		(28 "In13.Cu" signal "IN5")
		(30 "In14.Cu" signal "GND6")
		(32 "In15.Cu" signal "IN6")
		(34 "In16.Cu" signal "GND7")
		(2 "B.Cu" signal "BOTTOM")
		(9 "F.Adhes" user "F.Adhesive")
		(11 "B.Adhes" user "B.Adhesive")
		(13 "F.Paste" user "Package Geometry/Pastemask Top")
		(15 "B.Paste" user "Package Geometry/Pastemask Bottom")
		(5 "F.SilkS" user "Ref Des/Silkscreen Top")
		(7 "B.SilkS" user "Ref Des/Silkscreen Bottom")
		(1 "F.Mask" user "Board Geometry/Soldermask Top")
		(3 "B.Mask" user "Board Geometry/Soldermask Bottom")
		(17 "Dwgs.User" user "User.Drawings")
		(19 "Cmts.User" user "User.Comments")
		(21 "Eco1.User" user "User.Eco1")
		(23 "Eco2.User" user "User.Eco2")
		(25 "Edge.Cuts" user "Board Geometry/Outline")
		(27 "Margin" user)
		(31 "F.CrtYd" user "Package Geometry/Place Bound Top")
		(29 "B.CrtYd" user "Package Geometry/Place Bound Bottom")
		(35 "F.Fab" user "Ref Des/Assembly Top")
		(33 "B.Fab" user "Ref Des/Assembly Bottom")
	)
	(footprint ""
		(layer "B.Cu")
		(at 166.211504 -386.766562 90)
		(property "Reference" "C418"
			(at 0 0 90)
			(layer "B.SilkS")
			(hide yes)
			(effects
				(font
					(size 1.27 1.27)
				)
				(justify mirror)
			)
		)
		(property "Value" ""
			(at 0 0 90)
			(layer "B.Fab")
			(effects
				(font
					(size 1.27 1.27)
				)
				(justify mirror)
			)
		)
		(duplicate_pad_numbers_are_jumpers no)
		(fp_line
			(start 0.299974 -0.150114)
			(end -0.299974 -0.150114)
			(stroke
				(width 0.1)
				(type default)
			)
			(layer "B.Fab")
		)
		(fp_line
			(start -0.299974 -0.150114)
			(end -0.299974 0.150114)
			(stroke
				(width 0.1)
				(type default)
			)
			(layer "B.Fab")
		)
		(fp_line
			(start 0.299974 0.150114)
			(end 0.299974 -0.150114)
			(stroke
				(width 0.1)
				(type default)
			)
			(layer "B.Fab")
		)
		(fp_line
			(start -0.299974 0.150114)
			(end 0.299974 0.150114)
			(stroke
				(width 0.1)
				(type default)
			)
			(layer "B.Fab")
		)
		(pad "1" smd rect
			(at 0.2667 0 270)
			(size 0.3048 0.381)
			(layers "B.Cu" "B.Mask" "B.Paste")
			(net "P0V9_CPU1_RT2_2A")
		)
		(pad "2" smd rect
			(at -0.2667 0 270)
			(size 0.3048 0.381)
			(layers "B.Cu" "B.Mask" "B.Paste")
			(net "GND")
		)
	)
	(footprint ""
		(layer "B.Cu")
		(at 100.478844 -258.830318 180)
		(property "Reference" "C2507"
			(at 0 0 0)
			(layer "B.SilkS")
			(hide yes)
			(effects
				(font
					(size 1.27 1.27)
				)
				(justify mirror)
			)
		)
		(property "Value" ""
			(at 0 0 0)
			(layer "B.Fab")
			(effects
				(font
					(size 1.27 1.27)
				)
				(justify mirror)
			)
		)
		(duplicate_pad_numbers_are_jumpers no)
		(fp_line
			(start 0.7874 0.4064)
			(end 0.7874 -0.4064)
			(stroke
				(width 0.1524)
				(type default)
			)
			(layer "B.SilkS")
		)
		(fp_line
			(start 0.7874 -0.4064)
			(end -0.7874 -0.4064)
			(stroke
				(width 0.1524)
				(type default)
			)
			(layer "B.SilkS")
		)
		(fp_line
			(start -0.7874 0.4064)
			(end 0.7874 0.4064)
			(stroke
				(width 0.1524)
				(type default)
			)
			(layer "B.SilkS")
		)
		(fp_line
			(start -0.7874 -0.4064)
			(end -0.7874 0.4064)
			(stroke
				(width 0.1524)
				(type default)
			)
			(layer "B.SilkS")
		)
		(fp_line
			(start 0.67945 0.3048)
			(end 0.67945 -0.305054)
			(stroke
				(width 0.1)
				(type default)
			)
			(layer "B.Fab")
		)
		(fp_line
			(start 0.67945 -0.305054)
			(end 0.12065 -0.305054)
			(stroke
				(width 0.1)
				(type default)
			)
			(layer "B.Fab")
		)
		(fp_line
			(start 0.12065 0.3048)
			(end 0.67945 0.3048)
			(stroke
				(width 0.1)
				(type default)
			)
			(layer "B.Fab")
		)
		(fp_line
			(start 0.12065 0.2794)
			(end 0.12065 0.3048)
			(stroke
				(width 0.1)
				(type default)
			)
			(layer "B.Fab")
		)
		(fp_line
			(start 0.12065 -0.2794)
			(end -0.12065 -0.2794)
			(stroke
				(width 0.1)
				(type default)
			)
			(layer "B.Fab")
		)
		(fp_line
			(start 0.12065 -0.305054)
			(end 0.12065 -0.2794)
			(stroke
				(width 0.1)
				(type default)
			)
			(layer "B.Fab")
		)
		(fp_line
			(start -0.120396 0.3048)
			(end -0.120396 0.2794)
			(stroke
				(width 0.1)
				(type default)
			)
			(layer "B.Fab")
		)
		(fp_line
			(start -0.120396 0.2794)
			(end 0.12065 0.2794)
			(stroke
				(width 0.1)
				(type default)
			)
			(layer "B.Fab")
		)
		(fp_line
			(start -0.12065 -0.2794)
			(end -0.12065 -0.3048)
			(stroke
				(width 0.1)
				(type default)
			)
			(layer "B.Fab")
		)
		(fp_line
			(start -0.12065 -0.3048)
			(end -0.67945 -0.3048)
			(stroke
				(width 0.1)
				(type default)
			)
			(layer "B.Fab")
		)
		(fp_line
			(start -0.67945 0.3048)
			(end -0.120396 0.3048)
			(stroke
				(width 0.1)
				(type default)
			)
			(layer "B.Fab")
		)
		(fp_line
			(start -0.67945 -0.3048)
			(end -0.67945 0.3048)
			(stroke
				(width 0.1)
				(type default)
			)
			(layer "B.Fab")
		)
		(pad "1" smd circle
			(at 0.40005 0)
			(size 0 0)
			(layers "B.Cu" "B.Mask" "B.Paste")
			(net "PVDDIO_P1")
		)
		(pad "2" smd circle
			(at -0.40005 0)
			(size 0 0)
			(layers "B.Cu" "B.Mask" "B.Paste")
			(net "GND")
		)
	)
	(footprint ""
		(layer "B.Cu")
		(at 46.434502 -424.305984 -90)
		(property "Reference" "R2842"
			(at 0 0 90)
			(layer "B.SilkS")
			(hide yes)
			(effects
				(font
					(size 1.27 1.27)
				)
				(justify mirror)
			)
		)
		(property "Value" ""
			(at 0 0 90)
			(layer "B.Fab")
			(effects
				(font
					(size 1.27 1.27)
				)
				(justify mirror)
			)
		)
		(duplicate_pad_numbers_are_jumpers no)
		(fp_line
			(start -0.7874 0.4064)
			(end 0.7874 0.4064)
			(stroke
				(width 0.1524)
				(type default)
			)
			(layer "B.SilkS")
		)
		(fp_line
			(start 0.7874 0.4064)
			(end 0.7874 -0.4064)
			(stroke
				(width 0.1524)
				(type default)
			)
			(layer "B.SilkS")
		)
		(fp_line
			(start -0.7874 -0.4064)
			(end -0.7874 0.4064)
			(stroke
				(width 0.1524)
				(type default)
			)
			(layer "B.SilkS")
		)
		(fp_line
			(start 0.7874 -0.4064)
			(end -0.7874 -0.4064)
			(stroke
				(width 0.1524)
				(type default)
			)
			(layer "B.SilkS")
		)
		(fp_line
			(start -0.67945 0.3048)
			(end -0.120396 0.3048)
			(stroke
				(width 0.1)
				(type default)
			)
			(layer "B.Fab")
		)
		(fp_line
			(start -0.120396 0.3048)
			(end -0.120396 0.2794)
			(stroke
				(width 0.1)
				(type default)
			)
			(layer "B.Fab")
		)
		(fp_line
			(start 0.12065 0.3048)
			(end 0.67945 0.3048)
			(stroke
				(width 0.1)
				(type default)
			)
			(layer "B.Fab")
		)
		(fp_line
			(start 0.67945 0.3048)
			(end 0.67945 -0.305054)
			(stroke
				(width 0.1)
				(type default)
			)
			(layer "B.Fab")
		)
		(fp_line
			(start -0.120396 0.2794)
			(end 0.12065 0.2794)
			(stroke
				(width 0.1)
				(type default)
			)
			(layer "B.Fab")
		)
		(fp_line
			(start 0.12065 0.2794)
			(end 0.12065 0.3048)
			(stroke
				(width 0.1)
				(type default)
			)
			(layer "B.Fab")
		)
		(fp_line
			(start -0.12065 -0.2794)
			(end -0.12065 -0.3048)
			(stroke
				(width 0.1)
				(type default)
			)
			(layer "B.Fab")
		)
		(fp_line
			(start 0.12065 -0.2794)
			(end -0.12065 -0.2794)
			(stroke
				(width 0.1)
				(type default)
			)
			(layer "B.Fab")
		)
		(fp_line
			(start -0.67945 -0.3048)
			(end -0.67945 0.3048)
			(stroke
				(width 0.1)
				(type default)
			)
			(layer "B.Fab")
		)
		(fp_line
			(start -0.12065 -0.3048)
			(end -0.67945 -0.3048)
			(stroke
				(width 0.1)
				(type default)
			)
			(layer "B.Fab")
		)
		(fp_line
			(start 0.12065 -0.305054)
			(end 0.12065 -0.2794)
			(stroke
				(width 0.1)
				(type default)
			)
			(layer "B.Fab")
		)
		(fp_line
			(start 0.67945 -0.305054)
			(end 0.12065 -0.305054)
			(stroke
				(width 0.1)
				(type default)
			)
			(layer "B.Fab")
		)
		(pad "1" smd circle
			(at 0.40005 0 90)
			(size 0 0)
			(layers "B.Cu" "B.Mask" "B.Paste")
			(net "P3V3_AUX")
		)
		(pad "2" smd circle
			(at -0.40005 0 90)
			(size 0 0)
			(layers "B.Cu" "B.Mask" "B.Paste")
			(net "FM_GPU_PWRGD_N")
		)
	)
	(footprint ""
		(layer "B.Cu")
		(at 179.32146 -190.948564 180)
		(property "Reference" "R311"
			(at 0 0 0)
			(layer "B.SilkS")
			(hide yes)
			(effects
				(font
					(size 1.27 1.27)
				)
				(justify mirror)
			)
		)
		(property "Value" ""
			(at 0 0 0)
			(layer "B.Fab")
			(effects
				(font
					(size 1.27 1.27)
				)
				(justify mirror)
			)
		)
		(duplicate_pad_numbers_are_jumpers no)
		(fp_line
			(start 0.7874 0.4064)
			(end 0.7874 -0.4064)
			(stroke
				(width 0.1524)
				(type default)
			)
			(layer "B.SilkS")
		)
		(fp_line
			(start 0.7874 -0.4064)
			(end -0.7874 -0.4064)
			(stroke
				(width 0.1524)
				(type default)
			)
			(layer "B.SilkS")
		)
		(fp_line
			(start -0.7874 0.4064)
			(end 0.7874 0.4064)
			(stroke
				(width 0.1524)
				(type default)
			)
			(layer "B.SilkS")
		)
		(fp_line
			(start -0.7874 -0.4064)
			(end -0.7874 0.4064)
			(stroke
				(width 0.1524)
				(type default)
			)
			(layer "B.SilkS")
		)
		(fp_line
			(start 0.67945 0.3048)
			(end 0.67945 -0.305054)
			(stroke
				(width 0.1)
				(type default)
			)
			(layer "B.Fab")
		)
		(fp_line
			(start 0.67945 -0.305054)
			(end 0.12065 -0.305054)
			(stroke
				(width 0.1)
				(type default)
			)
			(layer "B.Fab")
		)
		(fp_line
			(start 0.12065 0.3048)
			(end 0.67945 0.3048)
			(stroke
				(width 0.1)
				(type default)
			)
			(layer "B.Fab")
		)
		(fp_line
			(start 0.12065 0.2794)
			(end 0.12065 0.3048)
			(stroke
				(width 0.1)
				(type default)
			)
			(layer "B.Fab")
		)
		(fp_line
			(start 0.12065 -0.2794)
			(end -0.12065 -0.2794)
			(stroke
				(width 0.1)
				(type default)
			)
			(layer "B.Fab")
		)
		(fp_line
			(start 0.12065 -0.305054)
			(end 0.12065 -0.2794)
			(stroke
				(width 0.1)
				(type default)
			)
			(layer "B.Fab")
		)
		(fp_line
			(start -0.120396 0.3048)
			(end -0.120396 0.2794)
			(stroke
				(width 0.1)
				(type default)
			)
			(layer "B.Fab")
		)
		(fp_line
			(start -0.120396 0.2794)
			(end 0.12065 0.2794)
			(stroke
				(width 0.1)
				(type default)
			)
			(layer "B.Fab")
		)
		(fp_line
			(start -0.12065 -0.2794)
			(end -0.12065 -0.3048)
			(stroke
				(width 0.1)
				(type default)
			)
			(layer "B.Fab")
		)
		(fp_line
			(start -0.12065 -0.3048)
			(end -0.67945 -0.3048)
			(stroke
				(width 0.1)
				(type default)
			)
			(layer "B.Fab")
		)
		(fp_line
			(start -0.67945 0.3048)
			(end -0.120396 0.3048)
			(stroke
				(width 0.1)
				(type default)
			)
			(layer "B.Fab")
		)
		(fp_line
			(start -0.67945 -0.3048)
			(end -0.67945 0.3048)
			(stroke
				(width 0.1)
				(type default)
			)
			(layer "B.Fab")
		)
		(pad "1" smd circle
			(at 0.40005 0)
			(size 0 0)
			(layers "B.Cu" "B.Mask" "B.Paste")
			(net "PWRGD_CHI_CPU1_DIMM")
		)
		(pad "2" smd circle
			(at -0.40005 0)
			(size 0 0)
			(layers "B.Cu" "B.Mask" "B.Paste")
			(net "PWRGD_CHGL_CPU1")
		)
	)
	(footprint ""
		(layer "B.Cu")
		(at 201.12355 -115.955572 180)
		(property "Reference" "R2"
			(at 0 0 0)
			(layer "B.SilkS")
			(hide yes)
			(effects
				(font
					(size 1.27 1.27)
				)
				(justify mirror)
			)
		)
		(property "Value" ""
			(at 0 0 0)
			(layer "B.Fab")
			(effects
				(font
					(size 1.27 1.27)
				)
				(justify mirror)
			)
		)
		(duplicate_pad_numbers_are_jumpers no)
		(fp_line
			(start 0.7874 0.4064)
			(end 0.7874 -0.4064)
			(stroke
				(width 0.1524)
				(type default)
			)
			(layer "B.SilkS")
		)
		(fp_line
			(start 0.7874 -0.4064)
			(end -0.7874 -0.4064)
			(stroke
				(width 0.1524)
				(type default)
			)
			(layer "B.SilkS")
		)
		(fp_line
			(start -0.7874 0.4064)
			(end 0.7874 0.4064)
			(stroke
				(width 0.1524)
				(type default)
			)
			(layer "B.SilkS")
		)
		(fp_line
			(start -0.7874 -0.4064)
			(end -0.7874 0.4064)
			(stroke
				(width 0.1524)
				(type default)
			)
			(layer "B.SilkS")
		)
		(fp_line
			(start 0.67945 0.3048)
			(end 0.67945 -0.305054)
			(stroke
				(width 0.1)
				(type default)
			)
			(layer "B.Fab")
		)
		(fp_line
			(start 0.67945 -0.305054)
			(end 0.12065 -0.305054)
			(stroke
				(width 0.1)
				(type default)
			)
			(layer "B.Fab")
		)
		(fp_line
			(start 0.12065 0.3048)
			(end 0.67945 0.3048)
			(stroke
				(width 0.1)
				(type default)
			)
			(layer "B.Fab")
		)
		(fp_line
			(start 0.12065 0.2794)
			(end 0.12065 0.3048)
			(stroke
				(width 0.1)
				(type default)
			)
			(layer "B.Fab")
		)
		(fp_line
			(start 0.12065 -0.2794)
			(end -0.12065 -0.2794)
			(stroke
				(width 0.1)
				(type default)
			)
			(layer "B.Fab")
		)
		(fp_line
			(start 0.12065 -0.305054)
			(end 0.12065 -0.2794)
			(stroke
				(width 0.1)
				(type default)
			)
			(layer "B.Fab")
		)
		(fp_line
			(start -0.120396 0.3048)
			(end -0.120396 0.2794)
			(stroke
				(width 0.1)
				(type default)
			)
			(layer "B.Fab")
		)
		(fp_line
			(start -0.120396 0.2794)
			(end 0.12065 0.2794)
			(stroke
				(width 0.1)
				(type default)
			)
			(layer "B.Fab")
		)
		(fp_line
			(start -0.12065 -0.2794)
			(end -0.12065 -0.3048)
			(stroke
				(width 0.1)
				(type default)
			)
			(layer "B.Fab")
		)
		(fp_line
			(start -0.12065 -0.3048)
			(end -0.67945 -0.3048)
			(stroke
				(width 0.1)
				(type default)
			)
			(layer "B.Fab")
		)
		(fp_line
			(start -0.67945 0.3048)
			(end -0.120396 0.3048)
			(stroke
				(width 0.1)
				(type default)
			)
			(layer "B.Fab")
		)
		(fp_line
			(start -0.67945 -0.3048)
			(end -0.67945 0.3048)
			(stroke
				(width 0.1)
				(type default)
			)
			(layer "B.Fab")
		)
		(pad "1" smd circle
			(at 0.40005 0)
			(size 0 0)
			(layers "B.Cu" "B.Mask" "B.Paste")
			(net "RST_PERST_CPU1_SWB_1_N")
		)
		(pad "2" smd circle
			(at -0.40005 0)
			(size 0 0)
			(layers "B.Cu" "B.Mask" "B.Paste")
			(net "RST_PERST_CPU1_SWB_1_R_N")
		)
	)
	(footprint ""
		(layer "B.Cu")
		(at 116.400326 -408.517344 90)
		(property "Reference" "C6726"
			(at 0 0 90)
			(layer "B.SilkS")
			(hide yes)
			(effects
				(font
					(size 1.27 1.27)
				)
				(justify mirror)
			)
		)
		(property "Value" ""
			(at 0 0 90)
			(layer "B.Fab")
			(effects
				(font
					(size 1.27 1.27)
				)
				(justify mirror)
			)
		)
		(duplicate_pad_numbers_are_jumpers no)
		(fp_line
			(start 0.299974 -0.150114)
			(end -0.299974 -0.150114)
			(stroke
				(width 0.1)
				(type default)
			)
			(layer "B.Fab")
		)
		(fp_line
			(start -0.299974 -0.150114)
			(end -0.299974 0.150114)
			(stroke
				(width 0.1)
				(type default)
			)
			(layer "B.Fab")
		)
		(fp_line
			(start 0.299974 0.150114)
			(end 0.299974 -0.150114)
			(stroke
				(width 0.1)
				(type default)
			)
			(layer "B.Fab")
		)
		(fp_line
			(start -0.299974 0.150114)
			(end 0.299974 0.150114)
			(stroke
				(width 0.1)
				(type default)
			)
			(layer "B.Fab")
		)
		(pad "1" smd rect
			(at 0.2667 0 270)
			(size 0.3048 0.381)
			(layers "B.Cu" "B.Mask" "B.Paste")
			(net "P5E_CPU1_P3_TX_BUF_C_DN<0>")
		)
		(pad "2" smd rect
			(at -0.2667 0 270)
			(size 0.3048 0.381)
			(layers "B.Cu" "B.Mask" "B.Paste")
			(net "P5E_CPU1_P3_TX_BUF_DN<0>")
		)
	)
	(footprint ""
		(layer "B.Cu")
		(at 105.960164 -257.455416 180)
		(property "Reference" "C2111"
			(at 0 0 0)
			(layer "B.SilkS")
			(hide yes)
			(effects
				(font
					(size 1.27 1.27)
				)
				(justify mirror)
			)
		)
		(property "Value" ""
			(at 0 0 0)
			(layer "B.Fab")
			(effects
				(font
					(size 1.27 1.27)
				)
				(justify mirror)
			)
		)
		(duplicate_pad_numbers_are_jumpers no)
		(fp_line
			(start 0.7874 0.4064)
			(end 0.7874 -0.4064)
			(stroke
				(width 0.1524)
				(type default)
			)
			(layer "B.SilkS")
		)
		(fp_line
			(start 0.7874 -0.4064)
			(end -0.7874 -0.4064)
			(stroke
				(width 0.1524)
				(type default)
			)
			(layer "B.SilkS")
		)
		(fp_line
			(start -0.7874 0.4064)
			(end 0.7874 0.4064)
			(stroke
				(width 0.1524)
				(type default)
			)
			(layer "B.SilkS")
		)
		(fp_line
			(start -0.7874 -0.4064)
			(end -0.7874 0.4064)
			(stroke
				(width 0.1524)
				(type default)
			)
			(layer "B.SilkS")
		)
		(fp_line
			(start 0.67945 0.3048)
			(end 0.67945 -0.305054)
			(stroke
				(width 0.1)
				(type default)
			)
			(layer "B.Fab")
		)
		(fp_line
			(start 0.67945 -0.305054)
			(end 0.12065 -0.305054)
			(stroke
				(width 0.1)
				(type default)
			)
			(layer "B.Fab")
		)
		(fp_line
			(start 0.12065 0.3048)
			(end 0.67945 0.3048)
			(stroke
				(width 0.1)
				(type default)
			)
			(layer "B.Fab")
		)
		(fp_line
			(start 0.12065 0.2794)
			(end 0.12065 0.3048)
			(stroke
				(width 0.1)
				(type default)
			)
			(layer "B.Fab")
		)
		(fp_line
			(start 0.12065 -0.2794)
			(end -0.12065 -0.2794)
			(stroke
				(width 0.1)
				(type default)
			)
			(layer "B.Fab")
		)
		(fp_line
			(start 0.12065 -0.305054)
			(end 0.12065 -0.2794)
			(stroke
				(width 0.1)
				(type default)
			)
			(layer "B.Fab")
		)
		(fp_line
			(start -0.120396 0.3048)
			(end -0.120396 0.2794)
			(stroke
				(width 0.1)
				(type default)
			)
			(layer "B.Fab")
		)
		(fp_line
			(start -0.120396 0.2794)
			(end 0.12065 0.2794)
			(stroke
				(width 0.1)
				(type default)
			)
			(layer "B.Fab")
		)
		(fp_line
			(start -0.12065 -0.2794)
			(end -0.12065 -0.3048)
			(stroke
				(width 0.1)
				(type default)
			)
			(layer "B.Fab")
		)
		(fp_line
			(start -0.12065 -0.3048)
			(end -0.67945 -0.3048)
			(stroke
				(width 0.1)
				(type default)
			)
			(layer "B.Fab")
		)
		(fp_line
			(start -0.67945 0.3048)
			(end -0.120396 0.3048)
			(stroke
				(width 0.1)
				(type default)
			)
			(layer "B.Fab")
		)
		(fp_line
			(start -0.67945 -0.3048)
			(end -0.67945 0.3048)
			(stroke
				(width 0.1)
				(type default)
			)
			(layer "B.Fab")
		)
		(pad "1" smd circle
			(at 0.40005 0)
			(size 0 0)
			(layers "B.Cu" "B.Mask" "B.Paste")
			(net "PVDDIO_P1")
		)
		(pad "2" smd circle
			(at -0.40005 0)
			(size 0 0)
			(layers "B.Cu" "B.Mask" "B.Paste")
			(net "GND")
		)
	)
	(footprint ""
		(layer "B.Cu")
		(at 229.8446 -336.296 180)
		(property "Reference" "R6759"
			(at 0 0 0)
			(layer "B.SilkS")
			(hide yes)
			(effects
				(font
					(size 1.27 1.27)
				)
				(justify mirror)
			)
		)
		(property "Value" ""
			(at 0 0 0)
			(layer "B.Fab")
			(effects
				(font
					(size 1.27 1.27)
				)
				(justify mirror)
			)
		)
		(duplicate_pad_numbers_are_jumpers no)
		(fp_line
			(start 0.32512 0.175006)
			(end 0.32512 -0.175006)
			(stroke
				(width 0.1)
				(type default)
			)
			(layer "B.Fab")
		)
		(fp_line
			(start 0.32512 -0.175006)
			(end -0.32512 -0.175006)
			(stroke
				(width 0.1)
				(type default)
			)
			(layer "B.Fab")
		)
		(fp_line
			(start -0.32512 0.175006)
			(end 0.32512 0.175006)
			(stroke
				(width 0.1)
				(type default)
			)
			(layer "B.Fab")
		)
		(fp_line
			(start -0.32512 -0.175006)
			(end -0.32512 0.175006)
			(stroke
				(width 0.1)
				(type default)
			)
			(layer "B.Fab")
		)
		(pad "1" smd rect
			(at 0.2667 0)
			(size 0.3048 0.381)
			(layers "B.Cu" "B.Mask" "B.Paste")
			(net "SMB_RT_CPU0_P3_SCL")
		)
		(pad "2" smd rect
			(at -0.2667 0 180)
			(size 0.3048 0.381)
			(layers "B.Cu" "B.Mask" "B.Paste")
			(net "SMB_RT_CPU0_P3_R_SCL")
		)
	)
)
